(kicad_pcb
	(version 20260206)
	(generator "pcbnew")
	(generator_version "10.0")
	(general
		(thickness 1.6)
		(legacy_teardrops no)
	)
	(paper "A4")
	(title_block
		(title "01162023_DA0F0TEBIF0_F0T_Expander_BD_F_brd_V02_OCP.brd")
		(comment 1 "Grand Teton / footprints 6102-6109 of 9728")
	)
	(layers
		(0 "F.Cu" signal "TOP")
		(4 "In1.Cu" signal "GND")
		(6 "In2.Cu" signal "VCC")
		(8 "In3.Cu" signal "VCC1")
		(10 "In4.Cu" signal "GND1")
		(12 "In5.Cu" signal "IN1")
		(14 "In6.Cu" signal "GND2")
		(16 "In7.Cu" signal "IN2")
		(18 "In8.Cu" signal "GND3")
		(20 "In9.Cu" signal "IN3")
		(22 "In10.Cu" signal "GND4")
		(24 "In11.Cu" signal "IN4")
		(26 "In12.Cu" signal "GND5")
		(28 "In13.Cu" signal "IN5")
		(30 "In14.Cu" signal "GND6")
		(32 "In15.Cu" signal "IN6")
		(34 "In16.Cu" signal "GND7")
		(2 "B.Cu" signal "BOTTOM")
		(9 "F.Adhes" user "F.Adhesive")
		(11 "B.Adhes" user "B.Adhesive")
		(13 "F.Paste" user "Package Geometry/Pastemask Top")
		(15 "B.Paste" user "Package Geometry/Pastemask Bottom")
		(5 "F.SilkS" user "Ref Des/Silkscreen Top")
		(7 "B.SilkS" user "Ref Des/Silkscreen Bottom")
		(1 "F.Mask" user "Board Geometry/Soldermask Top")
		(3 "B.Mask" user "Board Geometry/Soldermask Bottom")
		(17 "Dwgs.User" user "User.Drawings")
		(19 "Cmts.User" user "User.Comments")
		(21 "Eco1.User" user "User.Eco1")
		(23 "Eco2.User" user "User.Eco2")
		(25 "Edge.Cuts" user "Board Geometry/Outline")
		(27 "Margin" user)
		(31 "F.CrtYd" user "Package Geometry/Place Bound Top")
		(29 "B.CrtYd" user "Package Geometry/Place Bound Bottom")
		(35 "F.Fab" user "Ref Des/Assembly Top")
		(33 "B.Fab" user "Ref Des/Assembly Bottom")
	)
	(footprint ""
		(layer "F.Cu")
		(at 322.39712 -309.0418 135)
		(property "Reference" "R1385"
			(at 0 0 135)
			(layer "F.SilkS")
			(hide yes)
			(effects
				(font
					(size 1.27 1.27)
				)
			)
		)
		(property "Value" ""
			(at 0 0 135)
			(layer "F.Fab")
			(effects
				(font
					(size 1.27 1.27)
				)
			)
		)
		(duplicate_pad_numbers_are_jumpers no)
		(fp_line
			(start 0.787389 -0.406267)
			(end 0.787389 0.406267)
			(stroke
				(width 0.1524)
				(type default)
			)
			(layer "F.SilkS")
		)
		(fp_line
			(start 0.787389 0.406267)
			(end -0.787389 0.406267)
			(stroke
				(width 0.1524)
				(type default)
			)
			(layer "F.SilkS")
		)
		(fp_line
			(start -0.787389 -0.406267)
			(end 0.787389 -0.406267)
			(stroke
				(width 0.1524)
				(type default)
			)
			(layer "F.SilkS")
		)
		(fp_line
			(start -0.787389 0.406267)
			(end -0.787389 -0.406267)
			(stroke
				(width 0.1524)
				(type default)
			)
			(layer "F.SilkS")
		)
		(fp_line
			(start 0.679446 -0.30479)
			(end 0.679446 0.30479)
			(stroke
				(width 0.1)
				(type default)
			)
			(layer "F.Fab")
		)
		(fp_line
			(start 0.120515 -0.30479)
			(end 0.679446 -0.30479)
			(stroke
				(width 0.1)
				(type default)
			)
			(layer "F.Fab")
		)
		(fp_line
			(start 0.120695 -0.279466)
			(end 0.120515 -0.30479)
			(stroke
				(width 0.1)
				(type default)
			)
			(layer "F.Fab")
		)
		(fp_line
			(start 0.679446 0.30479)
			(end 0.120515 0.30479)
			(stroke
				(width 0.1)
				(type default)
			)
			(layer "F.Fab")
		)
		(fp_line
			(start -0.120695 -0.304969)
			(end -0.120695 -0.279466)
			(stroke
				(width 0.1)
				(type default)
			)
			(layer "F.Fab")
		)
		(fp_line
			(start -0.120695 -0.279466)
			(end 0.120695 -0.279466)
			(stroke
				(width 0.1)
				(type default)
			)
			(layer "F.Fab")
		)
		(fp_line
			(start 0.120335 0.279466)
			(end -0.120695 0.279466)
			(stroke
				(width 0.1)
				(type default)
			)
			(layer "F.Fab")
		)
		(fp_line
			(start 0.120515 0.30479)
			(end 0.120335 0.279466)
			(stroke
				(width 0.1)
				(type default)
			)
			(layer "F.Fab")
		)
		(fp_line
			(start -0.679446 -0.305149)
			(end -0.120695 -0.304969)
			(stroke
				(width 0.1)
				(type default)
			)
			(layer "F.Fab")
		)
		(fp_line
			(start -0.120695 0.279466)
			(end -0.120515 0.30479)
			(stroke
				(width 0.1)
				(type default)
			)
			(layer "F.Fab")
		)
		(fp_line
			(start -0.120515 0.30479)
			(end -0.679446 0.30479)
			(stroke
				(width 0.1)
				(type default)
			)
			(layer "F.Fab")
		)
		(fp_line
			(start -0.679446 0.30479)
			(end -0.679446 -0.305149)
			(stroke
				(width 0.1)
				(type default)
			)
			(layer "F.Fab")
		)
		(pad "1" smd circle
			(at -0.40005 0 135)
			(size 0 0)
			(layers "F.Cu" "F.Mask" "F.Paste")
			(net "GND")
		)
		(pad "2" smd circle
			(at 0.40005 0 135)
			(size 0 0)
			(layers "F.Cu" "F.Mask" "F.Paste")
			(net "PEX2_SPARE2")
		)
	)
	(footprint ""
		(layer "F.Cu")
		(at 35.3695 -260.088634 -90)
		(property "Reference" "R4561"
			(at 0 0 270)
			(layer "F.SilkS")
			(hide yes)
			(effects
				(font
					(size 1.27 1.27)
				)
			)
		)
		(property "Value" ""
			(at 0 0 270)
			(layer "F.Fab")
			(effects
				(font
					(size 1.27 1.27)
				)
			)
		)
		(duplicate_pad_numbers_are_jumpers no)
		(fp_line
			(start -0.7874 0.4064)
			(end -0.7874 -0.4064)
			(stroke
				(width 0.1524)
				(type default)
			)
			(layer "F.SilkS")
		)
		(fp_line
			(start 0.7874 0.4064)
			(end -0.7874 0.4064)
			(stroke
				(width 0.1524)
				(type default)
			)
			(layer "F.SilkS")
		)
		(fp_line
			(start -0.7874 -0.4064)
			(end 0.7874 -0.4064)
			(stroke
				(width 0.1524)
				(type default)
			)
			(layer "F.SilkS")
		)
		(fp_line
			(start 0.7874 -0.4064)
			(end 0.7874 0.4064)
			(stroke
				(width 0.1524)
				(type default)
			)
			(layer "F.SilkS")
		)
		(fp_line
			(start -0.67945 0.3048)
			(end -0.67945 -0.305054)
			(stroke
				(width 0.1)
				(type default)
			)
			(layer "F.Fab")
		)
		(fp_line
			(start -0.12065 0.3048)
			(end -0.67945 0.3048)
			(stroke
				(width 0.1)
				(type default)
			)
			(layer "F.Fab")
		)
		(fp_line
			(start 0.120396 0.3048)
			(end 0.120396 0.2794)
			(stroke
				(width 0.1)
				(type default)
			)
			(layer "F.Fab")
		)
		(fp_line
			(start 0.67945 0.3048)
			(end 0.120396 0.3048)
			(stroke
				(width 0.1)
				(type default)
			)
			(layer "F.Fab")
		)
		(fp_line
			(start -0.12065 0.2794)
			(end -0.12065 0.3048)
			(stroke
				(width 0.1)
				(type default)
			)
			(layer "F.Fab")
		)
		(fp_line
			(start 0.120396 0.2794)
			(end -0.12065 0.2794)
			(stroke
				(width 0.1)
				(type default)
			)
			(layer "F.Fab")
		)
		(fp_line
			(start -0.12065 -0.2794)
			(end 0.12065 -0.2794)
			(stroke
				(width 0.1)
				(type default)
			)
			(layer "F.Fab")
		)
		(fp_line
			(start 0.12065 -0.2794)
			(end 0.12065 -0.3048)
			(stroke
				(width 0.1)
				(type default)
			)
			(layer "F.Fab")
		)
		(fp_line
			(start 0.12065 -0.3048)
			(end 0.67945 -0.3048)
			(stroke
				(width 0.1)
				(type default)
			)
			(layer "F.Fab")
		)
		(fp_line
			(start 0.67945 -0.3048)
			(end 0.67945 0.3048)
			(stroke
				(width 0.1)
				(type default)
			)
			(layer "F.Fab")
		)
		(fp_line
			(start -0.67945 -0.305054)
			(end -0.12065 -0.305054)
			(stroke
				(width 0.1)
				(type default)
			)
			(layer "F.Fab")
		)
		(fp_line
			(start -0.12065 -0.305054)
			(end -0.12065 -0.2794)
			(stroke
				(width 0.1)
				(type default)
			)
			(layer "F.Fab")
		)
		(pad "1" smd circle
			(at -0.40005 0 270)
			(size 0 0)
			(layers "F.Cu" "F.Mask" "F.Paste")
			(net "PCEPLL3_VDDA18_PEX0")
		)
		(pad "2" smd circle
			(at 0.40005 0 270)
			(size 0 0)
			(layers "F.Cu" "F.Mask" "F.Paste")
			(net "PCEPLL3_VDDA18_PEX0_R")
		)
	)
	(footprint ""
		(layer "F.Cu")
		(at 449.862702 -100.406708 -90)
		(property "Reference" "PC331"
			(at 0 0 270)
			(layer "F.SilkS")
			(hide yes)
			(effects
				(font
					(size 1.27 1.27)
				)
			)
		)
		(property "Value" ""
			(at 0 0 270)
			(layer "F.Fab")
			(effects
				(font
					(size 1.27 1.27)
				)
			)
		)
		(duplicate_pad_numbers_are_jumpers no)
		(fp_line
			(start -1.524 0.762)
			(end -1.524 -0.762)
			(stroke
				(width 0.1524)
				(type default)
			)
			(layer "F.SilkS")
		)
		(fp_line
			(start 1.524 0.762)
			(end -1.524 0.762)
			(stroke
				(width 0.1524)
				(type default)
			)
			(layer "F.SilkS")
		)
		(fp_line
			(start -1.524 -0.762)
			(end 1.524 -0.762)
			(stroke
				(width 0.1524)
				(type default)
			)
			(layer "F.SilkS")
		)
		(fp_line
			(start 1.524 -0.762)
			(end 1.524 0.762)
			(stroke
				(width 0.1524)
				(type default)
			)
			(layer "F.SilkS")
		)
		(fp_line
			(start -1.1049 0.724916)
			(end 1.1049 0.724916)
			(stroke
				(width 0.1)
				(type default)
			)
			(layer "F.Fab")
		)
		(fp_line
			(start 1.1049 0.724916)
			(end 1.1049 -0.724916)
			(stroke
				(width 0.1)
				(type default)
			)
			(layer "F.Fab")
		)
		(fp_line
			(start -1.1049 -0.724916)
			(end -1.1049 0.724916)
			(stroke
				(width 0.1)
				(type default)
			)
			(layer "F.Fab")
		)
		(fp_line
			(start 1.1049 -0.724916)
			(end -1.1049 -0.724916)
			(stroke
				(width 0.1)
				(type default)
			)
			(layer "F.Fab")
		)
		(pad "1" smd rect
			(at -0.889 0 90)
			(size 1.016 1.27)
			(layers "F.Cu" "F.Mask" "F.Paste")
			(net "GND")
		)
		(pad "2" smd rect
			(at 0.889 0 90)
			(size 1.016 1.27)
			(layers "F.Cu" "F.Mask" "F.Paste")
			(net "P12V_AUX")
		)
	)
	(footprint ""
		(layer "F.Cu")
		(at 497.694712 -548.965882 180)
		(property "Reference" "SCREW_0"
			(at -3.2385 -1.402334 0)
			(unlocked yes)
			(layer "B.SilkS")
			(effects
				(font
					(size 0.7874 0.5842)
					(thickness 0.1524)
				)
				(justify mirror)
			)
		)
		(property "Value" ""
			(at 0 0 180)
			(layer "F.Fab")
			(effects
				(font
					(size 1.27 1.27)
				)
			)
		)
		(duplicate_pad_numbers_are_jumpers no)
		(pad "1" thru_hole circle
			(at 0 0 180)
			(size 0.4572 0.4572)
			(drill 0.2032)
			(layers "*.Cu" "*.Mask")
			(remove_unused_layers no)
			(net "Net_9164")
			(clearance 0.127)
			(thermal_gap 0.127)
			(padstack
				(mode front_inner_back)
				(layer "Inner"
					(shape circle)
					(size 0.4572 0.4572)
					(clearance 0.127)
				)
				(layer "B.Cu"
					(shape circle)
					(size 0.508 0.508)
					(clearance 0.1016)
				)
			)
		)
	)
	(footprint ""
		(layer "F.Cu")
		(at 77.806042 -350.098614 90)
		(property "Reference" "C144"
			(at 0 0 90)
			(layer "F.SilkS")
			(hide yes)
			(effects
				(font
					(size 1.27 1.27)
				)
			)
		)
		(property "Value" ""
			(at 0 0 90)
			(layer "F.Fab")
			(effects
				(font
					(size 1.27 1.27)
				)
			)
		)
		(duplicate_pad_numbers_are_jumpers no)
		(fp_line
			(start 0.299974 -0.150114)
			(end 0.299974 0.150114)
			(stroke
				(width 0.1)
				(type default)
			)
			(layer "F.Fab")
		)
		(fp_line
			(start -0.299974 -0.150114)
			(end 0.299974 -0.150114)
			(stroke
				(width 0.1)
				(type default)
			)
			(layer "F.Fab")
		)
		(fp_line
			(start 0.299974 0.150114)
			(end -0.299974 0.150114)
			(stroke
				(width 0.1)
				(type default)
			)
			(layer "F.Fab")
		)
		(fp_line
			(start -0.299974 0.150114)
			(end -0.299974 -0.150114)
			(stroke
				(width 0.1)
				(type default)
			)
			(layer "F.Fab")
		)
		(pad "1" smd rect
			(at -0.2667 0 90)
			(size 0.3048 0.381)
			(layers "F.Cu" "F.Mask" "F.Paste")
			(net "P5E_PEX0_STN6_TX_DN<104>")
		)
		(pad "2" smd rect
			(at 0.2667 0 90)
			(size 0.3048 0.381)
			(layers "F.Cu" "F.Mask" "F.Paste")
			(net "P5E_PEX0_STN6_TX_C_DN<104>")
		)
	)
	(footprint ""
		(layer "F.Cu")
		(at 252.98146 -195.573396 -90)
		(property "Reference" "R4301"
			(at 0 0 270)
			(layer "F.SilkS")
			(hide yes)
			(effects
				(font
					(size 1.27 1.27)
				)
			)
		)
		(property "Value" ""
			(at 0 0 270)
			(layer "F.Fab")
			(effects
				(font
					(size 1.27 1.27)
				)
			)
		)
		(duplicate_pad_numbers_are_jumpers no)
		(fp_line
			(start -0.7874 0.4064)
			(end -0.7874 -0.4064)
			(stroke
				(width 0.1524)
				(type default)
			)
			(layer "F.SilkS")
		)
		(fp_line
			(start 0.7874 0.4064)
			(end -0.7874 0.4064)
			(stroke
				(width 0.1524)
				(type default)
			)
			(layer "F.SilkS")
		)
		(fp_line
			(start -0.7874 -0.4064)
			(end 0.7874 -0.4064)
			(stroke
				(width 0.1524)
				(type default)
			)
			(layer "F.SilkS")
		)
		(fp_line
			(start 0.7874 -0.4064)
			(end 0.7874 0.4064)
			(stroke
				(width 0.1524)
				(type default)
			)
			(layer "F.SilkS")
		)
		(fp_line
			(start -0.67945 0.3048)
			(end -0.67945 -0.305054)
			(stroke
				(width 0.1)
				(type default)
			)
			(layer "F.Fab")
		)
		(fp_line
			(start -0.12065 0.3048)
			(end -0.67945 0.3048)
			(stroke
				(width 0.1)
				(type default)
			)
			(layer "F.Fab")
		)
		(fp_line
			(start 0.120396 0.3048)
			(end 0.120396 0.2794)
			(stroke
				(width 0.1)
				(type default)
			)
			(layer "F.Fab")
		)
		(fp_line
			(start 0.67945 0.3048)
			(end 0.120396 0.3048)
			(stroke
				(width 0.1)
				(type default)
			)
			(layer "F.Fab")
		)
		(fp_line
			(start -0.12065 0.2794)
			(end -0.12065 0.3048)
			(stroke
				(width 0.1)
				(type default)
			)
			(layer "F.Fab")
		)
		(fp_line
			(start 0.120396 0.2794)
			(end -0.12065 0.2794)
			(stroke
				(width 0.1)
				(type default)
			)
			(layer "F.Fab")
		)
		(fp_line
			(start -0.12065 -0.2794)
			(end 0.12065 -0.2794)
			(stroke
				(width 0.1)
				(type default)
			)
			(layer "F.Fab")
		)
		(fp_line
			(start 0.12065 -0.2794)
			(end 0.12065 -0.3048)
			(stroke
				(width 0.1)
				(type default)
			)
			(layer "F.Fab")
		)
		(fp_line
			(start 0.12065 -0.3048)
			(end 0.67945 -0.3048)
			(stroke
				(width 0.1)
				(type default)
			)
			(layer "F.Fab")
		)
		(fp_line
			(start 0.67945 -0.3048)
			(end 0.67945 0.3048)
			(stroke
				(width 0.1)
				(type default)
			)
			(layer "F.Fab")
		)
		(fp_line
			(start -0.67945 -0.305054)
			(end -0.12065 -0.305054)
			(stroke
				(width 0.1)
				(type default)
			)
			(layer "F.Fab")
		)
		(fp_line
			(start -0.12065 -0.305054)
			(end -0.12065 -0.2794)
			(stroke
				(width 0.1)
				(type default)
			)
			(layer "F.Fab")
		)
		(pad "1" smd circle
			(at -0.40005 0 270)
			(size 0 0)
			(layers "F.Cu" "F.Mask" "F.Paste")
			(net "JTAG_PLD_TCK")
		)
		(pad "2" smd circle
			(at 0.40005 0 270)
			(size 0 0)
			(layers "F.Cu" "F.Mask" "F.Paste")
			(net "JTAG_FPGA_TCK")
		)
	)
	(footprint ""
		(layer "F.Cu")
		(at 458.68971 -273.224752)
		(property "Reference" "C4389"
			(at 0 0 0)
			(layer "F.SilkS")
			(hide yes)
			(effects
				(font
					(size 1.27 1.27)
				)
			)
		)
		(property "Value" ""
			(at 0 0 0)
			(layer "F.Fab")
			(effects
				(font
					(size 1.27 1.27)
				)
			)
		)
		(duplicate_pad_numbers_are_jumpers no)
		(fp_line
			(start -1.2954 -0.5842)
			(end 1.2954 -0.5842)
			(stroke
				(width 0.1524)
				(type default)
			)
			(layer "F.SilkS")
		)
		(fp_line
			(start -1.2954 0.5842)
			(end -1.2954 -0.5842)
			(stroke
				(width 0.1524)
				(type default)
			)
			(layer "F.SilkS")
		)
		(fp_line
			(start 1.2954 -0.5842)
			(end 1.2954 0.5842)
			(stroke
				(width 0.1524)
				(type default)
			)
			(layer "F.SilkS")
		)
		(fp_line
			(start 1.2954 0.5842)
			(end -1.2954 0.5842)
			(stroke
				(width 0.1524)
				(type default)
			)
			(layer "F.SilkS")
		)
		(fp_line
			(start -1.1938 -0.4064)
			(end -0.8636 -0.4064)
			(stroke
				(width 0.1)
				(type default)
			)
			(layer "F.Fab")
		)
		(fp_line
			(start -1.1938 0.4064)
			(end -1.1938 -0.4064)
			(stroke
				(width 0.1)
				(type default)
			)
			(layer "F.Fab")
		)
		(fp_line
			(start -0.8636 -0.4572)
			(end 0.8636 -0.4572)
			(stroke
				(width 0.1)
				(type default)
			)
			(layer "F.Fab")
		)
		(fp_line
			(start -0.8636 -0.4064)
			(end -0.8636 -0.4572)
			(stroke
				(width 0.1)
				(type default)
			)
			(layer "F.Fab")
		)
		(fp_line
			(start -0.8636 0.4064)
			(end -1.1938 0.4064)
			(stroke
				(width 0.1)
				(type default)
			)
			(layer "F.Fab")
		)
		(fp_line
			(start -0.8636 0.4572)
			(end -0.8636 0.4064)
			(stroke
				(width 0.1)
				(type default)
			)
			(layer "F.Fab")
		)
		(fp_line
			(start 0.8636 -0.4572)
			(end 0.8636 -0.4064)
			(stroke
				(width 0.1)
				(type default)
			)
			(layer "F.Fab")
		)
		(fp_line
			(start 0.8636 -0.4064)
			(end 1.1938 -0.4064)
			(stroke
				(width 0.1)
				(type default)
			)
			(layer "F.Fab")
		)
		(fp_line
			(start 0.8636 0.4064)
			(end 0.8636 0.4572)
			(stroke
				(width 0.1)
				(type default)
			)
			(layer "F.Fab")
		)
		(fp_line
			(start 0.8636 0.4572)
			(end -0.8636 0.4572)
			(stroke
				(width 0.1)
				(type default)
			)
			(layer "F.Fab")
		)
		(fp_line
			(start 1.1938 -0.4064)
			(end 1.1938 0.4064)
			(stroke
				(width 0.1)
				(type default)
			)
			(layer "F.Fab")
		)
		(fp_line
			(start 1.1938 0.4064)
			(end 0.8636 0.4064)
			(stroke
				(width 0.1)
				(type default)
			)
			(layer "F.Fab")
		)
		(pad "1" smd rect
			(at -0.7366 0 270)
			(size 0.7112 0.8128)
			(layers "F.Cu" "F.Mask" "F.Paste")
			(net "P1V25_PEX3")
		)
		(pad "2" smd rect
			(at 0.7366 0 270)
			(size 0.7112 0.8128)
			(layers "F.Cu" "F.Mask" "F.Paste")
			(net "GND")
		)
	)
	(footprint ""
		(layer "F.Cu")
		(at 60.17895 -59.577986 -90)
		(property "Reference" "R890"
			(at 0 0 270)
			(layer "F.SilkS")
			(hide yes)
			(effects
				(font
					(size 1.27 1.27)
				)
			)
		)
		(property "Value" ""
			(at 0 0 270)
			(layer "F.Fab")
			(effects
				(font
					(size 1.27 1.27)
				)
			)
		)
		(duplicate_pad_numbers_are_jumpers no)
		(fp_line
			(start -0.7874 0.4064)
			(end -0.7874 -0.4064)
			(stroke
				(width 0.1524)
				(type default)
			)
			(layer "F.SilkS")
		)
		(fp_line
			(start 0.7874 0.4064)
			(end -0.7874 0.4064)
			(stroke
				(width 0.1524)
				(type default)
			)
			(layer "F.SilkS")
		)
		(fp_line
			(start -0.7874 -0.4064)
			(end 0.7874 -0.4064)
			(stroke
				(width 0.1524)
				(type default)
			)
			(layer "F.SilkS")
		)
		(fp_line
			(start 0.7874 -0.4064)
			(end 0.7874 0.4064)
			(stroke
				(width 0.1524)
				(type default)
			)
			(layer "F.SilkS")
		)
		(fp_line
			(start -0.67945 0.3048)
			(end -0.67945 -0.305054)
			(stroke
				(width 0.1)
				(type default)
			)
			(layer "F.Fab")
		)
		(fp_line
			(start -0.12065 0.3048)
			(end -0.67945 0.3048)
			(stroke
				(width 0.1)
				(type default)
			)
			(layer "F.Fab")
		)
		(fp_line
			(start 0.120396 0.3048)
			(end 0.120396 0.2794)
			(stroke
				(width 0.1)
				(type default)
			)
			(layer "F.Fab")
		)
		(fp_line
			(start 0.67945 0.3048)
			(end 0.120396 0.3048)
			(stroke
				(width 0.1)
				(type default)
			)
			(layer "F.Fab")
		)
		(fp_line
			(start -0.12065 0.2794)
			(end -0.12065 0.3048)
			(stroke
				(width 0.1)
				(type default)
			)
			(layer "F.Fab")
		)
		(fp_line
			(start 0.120396 0.2794)
			(end -0.12065 0.2794)
			(stroke
				(width 0.1)
				(type default)
			)
			(layer "F.Fab")
		)
		(fp_line
			(start -0.12065 -0.2794)
			(end 0.12065 -0.2794)
			(stroke
				(width 0.1)
				(type default)
			)
			(layer "F.Fab")
		)
		(fp_line
			(start 0.12065 -0.2794)
			(end 0.12065 -0.3048)
			(stroke
				(width 0.1)
				(type default)
			)
			(layer "F.Fab")
		)
		(fp_line
			(start 0.12065 -0.3048)
			(end 0.67945 -0.3048)
			(stroke
				(width 0.1)
				(type default)
			)
			(layer "F.Fab")
		)
		(fp_line
			(start 0.67945 -0.3048)
			(end 0.67945 0.3048)
			(stroke
				(width 0.1)
				(type default)
			)
			(layer "F.Fab")
		)
		(fp_line
			(start -0.67945 -0.305054)
			(end -0.12065 -0.305054)
			(stroke
				(width 0.1)
				(type default)
			)
			(layer "F.Fab")
		)
		(fp_line
			(start -0.12065 -0.305054)
			(end -0.12065 -0.2794)
			(stroke
				(width 0.1)
				(type default)
			)
			(layer "F.Fab")
		)
		(pad "1" smd circle
			(at -0.40005 0 270)
			(size 0 0)
			(layers "F.Cu" "F.Mask" "F.Paste")
			(net "P3V3_SSD2")
		)
		(pad "2" smd circle
			(at 0.40005 0 270)
			(size 0 0)
			(layers "F.Cu" "F.Mask" "F.Paste")
			(net "PWRGD_P3V3_SSD2")
		)
	)
)
